(kicad_pcb
	(version 20260206)
	(generator "pcbnew")
	(generator_version "10.0")
	(general
		(thickness 1.6)
		(legacy_teardrops no)
	)
	(paper "A4")
	(title_block
		(title "9052_F0T_PDB_Converter_Brick_F_V03_1208_1600_OCP.brd")
		(comment 1 "Grand Teton / footprints 205-206 of 578")
	)
	(layers
		(0 "F.Cu" signal "TOP")
		(4 "In1.Cu" signal "GND")
		(6 "In2.Cu" signal "IN1")
		(8 "In3.Cu" signal "GND1")
		(10 "In4.Cu" signal "VCC")
		(12 "In5.Cu" signal "VCC1")
		(14 "In6.Cu" signal "GND2")
		(16 "In7.Cu" signal "IN2")
		(18 "In8.Cu" signal "GND3")
		(2 "B.Cu" signal "BOTTOM")
		(9 "F.Adhes" user "F.Adhesive")
		(11 "B.Adhes" user "B.Adhesive")
		(13 "F.Paste" user "Package Geometry/Pastemask Top")
		(15 "B.Paste" user "Package Geometry/Pastemask Bottom")
		(5 "F.SilkS" user "Ref Des/Silkscreen Top")
		(7 "B.SilkS" user "Ref Des/Silkscreen Bottom")
		(1 "F.Mask" user "Board Geometry/Soldermask Top")
		(3 "B.Mask" user "Board Geometry/Soldermask Bottom")
		(17 "Dwgs.User" user "User.Drawings")
		(19 "Cmts.User" user "User.Comments")
		(21 "Eco1.User" user "User.Eco1")
		(23 "Eco2.User" user "User.Eco2")
		(25 "Edge.Cuts" user "Board Geometry/Outline")
		(27 "Margin" user)
		(31 "F.CrtYd" user "Package Geometry/Place Bound Top")
		(29 "B.CrtYd" user "Package Geometry/Place Bound Bottom")
		(35 "F.Fab" user "Ref Des/Assembly Top")
		(33 "B.Fab" user "Ref Des/Assembly Bottom")
	)
	(footprint ""
		(layer "F.Cu")
		(at 32.004 -65.659 180)
		(property "Reference" "D5"
			(at 4.1656 2.25933 0)
			(unlocked yes)
			(layer "F.SilkS")
			(effects
				(font
					(size 0.7874 0.5842)
					(thickness 0.1524)
				)
				(justify left)
			)
		)
		(property "Value" ""
			(at 0 0 180)
			(layer "F.Fab")
			(effects
				(font
					(size 1.27 1.27)
				)
			)
		)
		(duplicate_pad_numbers_are_jumpers no)
		(fp_line
			(start 4.107942 1.459992)
			(end -3.400044 1.459992)
			(stroke
				(width 0.1524)
				(type default)
			)
			(layer "F.SilkS")
		)
		(fp_line
			(start 4.107942 -1.459992)
			(end 4.107942 1.459992)
			(stroke
				(width 0.1524)
				(type default)
			)
			(layer "F.SilkS")
		)
		(fp_line
			(start -3.400044 1.459992)
			(end -3.400044 -1.459992)
			(stroke
				(width 0.1524)
				(type default)
			)
			(layer "F.SilkS")
		)
		(fp_line
			(start -3.400044 -1.459992)
			(end 4.107942 -1.459992)
			(stroke
				(width 0.1524)
				(type default)
			)
			(layer "F.SilkS")
		)
		(fp_poly
			(pts
				(xy 4.107942 -1.459992) (xy 4.107942 1.459992) (xy 3.308096 1.459992) (xy 3.308096 -1.459992)
			)
			(stroke
				(width 0)
				(type default)
			)
			(fill yes)
			(layer "F.SilkS")
		)
		(fp_line
			(start 2.29997 1.459992)
			(end -2.29997 1.459992)
			(stroke
				(width 0.1)
				(type default)
			)
			(layer "F.Fab")
		)
		(fp_line
			(start 2.29997 -1.459992)
			(end 2.29997 1.459992)
			(stroke
				(width 0.1)
				(type default)
			)
			(layer "F.Fab")
		)
		(fp_line
			(start -2.29997 1.459992)
			(end -2.29997 -1.459992)
			(stroke
				(width 0.1)
				(type default)
			)
			(layer "F.Fab")
		)
		(fp_line
			(start -2.29997 -1.459992)
			(end 2.29997 -1.459992)
			(stroke
				(width 0.1)
				(type default)
			)
			(layer "F.Fab")
		)
		(fp_text user "-"
			(at 6.1976 0.09525 0)
			(unlocked yes)
			(layer "F.SilkS")
			(effects
				(font
					(size 1.905 1.4224)
					(thickness 0.1524)
				)
				(justify left)
			)
		)
		(fp_text user "+"
			(at -4.8514 0.92075 180)
			(unlocked yes)
			(layer "F.SilkS")
			(effects
				(font
					(size 1.905 1.4224)
					(thickness 0.1524)
				)
				(justify left)
			)
		)
		(fp_text user "-"
			(at 5.4102 0.29845 0)
			(unlocked yes)
			(layer "F.Fab")
			(effects
				(font
					(size 1.905 1.4224)
					(thickness 0.1524)
				)
				(justify left)
			)
		)
		(fp_text user "+"
			(at -4.7752 -0.12065 180)
			(unlocked yes)
			(layer "F.Fab")
			(effects
				(font
					(size 1.905 1.4224)
					(thickness 0.1524)
				)
				(justify left)
			)
		)
		(pad "A" smd rect
			(at -1.999996 0 270)
			(size 1.7018 2.5146)
			(layers "F.Cu" "F.Mask" "F.Paste")
			(net "GND")
		)
		(pad "C" smd rect
			(at 1.999996 0 270)
			(size 1.7018 2.5146)
			(layers "F.Cu" "F.Mask" "F.Paste")
			(net "P12V_HPDB")
		)
	)
	(footprint ""
		(layer "F.Cu")
		(at 129.999994 -11.999976 -90)
		(property "Reference" "H4"
			(at -6.261354 11.508994 0)
			(unlocked yes)
			(layer "F.SilkS")
			(effects
				(font
					(size 0.7874 0.5842)
					(thickness 0.1524)
				)
				(justify left)
			)
		)
		(property "Value" ""
			(at 0 0 270)
			(layer "F.Fab")
			(effects
				(font
					(size 1.27 1.27)
				)
			)
		)
		(duplicate_pad_numbers_are_jumpers no)
		(pad "1" thru_hole oval
			(at 0 0 270)
			(size 10.0076 32.004)
			(drill 3.0226
				(offset 0 10.999978)
			)
			(layers "*.Cu" "*.Mask")
			(remove_unused_layers no)
			(net "GND")
			(clearance -1.995678)
			(padstack
				(mode front_inner_back)
				(layer "Inner"
					(shape circle)
					(size 0 0)
					(clearance 0)
				)
				(layer "B.Cu"
					(shape oval)
					(size 10.0076 32.004)
					(offset 0 10.999978)
					(clearance -1.995678)
				)
			)
		)
	)
)
